(kicad_pcb
	(version 20260206)
	(generator "pcbnew")
	(generator_version "10.0")
	(general
		(thickness 1.6)
		(legacy_teardrops no)
	)
	(paper "A4")
	(title_block
		(title "baseboard — 13948-1b.1110WZS1818.brd")
		(comment 1 "Honey Badger (Wiwynn) / footprints 1219-1224 of 2523")
	)
	(layers
		(0 "F.Cu" signal "TOP")
		(4 "In1.Cu" signal "L2GND")
		(6 "In2.Cu" signal "L3")
		(8 "In3.Cu" signal "L4VCC")
		(10 "In4.Cu" signal "L5VCC")
		(12 "In5.Cu" signal "L6")
		(14 "In6.Cu" signal "L7GND")
		(2 "B.Cu" signal "BOTTOM")
		(9 "F.Adhes" user "F.Adhesive")
		(11 "B.Adhes" user "B.Adhesive")
		(13 "F.Paste" user "Package Geometry/Pastemask Top")
		(15 "B.Paste" user "Package Geometry/Pastemask Bottom")
		(5 "F.SilkS" user "Ref Des/Silkscreen Top")
		(7 "B.SilkS" user "Ref Des/Silkscreen Bottom")
		(1 "F.Mask" user "Board Geometry/Soldermask Top")
		(3 "B.Mask" user "Board Geometry/Soldermask Bottom")
		(17 "Dwgs.User" user "User.Drawings")
		(19 "Cmts.User" user "User.Comments")
		(21 "Eco1.User" user "User.Eco1")
		(23 "Eco2.User" user "User.Eco2")
		(25 "Edge.Cuts" user "Board Geometry/Outline")
		(27 "Margin" user)
		(31 "F.CrtYd" user "Package Geometry/Place Bound Top")
		(29 "B.CrtYd" user "Package Geometry/Place Bound Bottom")
		(35 "F.Fab" user "Ref Des/Assembly Top")
		(33 "B.Fab" user "Ref Des/Assembly Bottom")
	)
	(footprint ""
		(layer "F.Cu")
		(at 82.784188 -19.119596 90)
		(property "Reference" "PU13"
			(at 0 0 90)
			(layer "F.SilkS")
			(hide yes)
			(effects
				(font
					(size 1.27 1.27)
				)
			)
		)
		(property "Value" "VT235WFQX-ADJ-1-GP"
			(at -5.8166 -7.7216 90)
			(unlocked yes)
			(layer "F.Fab")
			(hide yes)
			(effects
				(font
					(size 1.016 1.016)
					(thickness 0.1524)
				)
			)
		)
		(property "Device Type" "QFN19-1H40"
			(at -5.8166 -9.2456 90)
			(unlocked yes)
			(layer "F.Fab")
			(hide yes)
			(effects
				(font
					(size 1.016 1.016)
					(thickness 0.1524)
				)
			)
		)
		(duplicate_pad_numbers_are_jumpers no)
		(fp_line
			(start -1.4859 -3.0734)
			(end -2.7559 -3.0734)
			(stroke
				(width 0.1524)
				(type default)
			)
			(layer "F.SilkS")
		)
		(fp_line
			(start -2.7559 -3.0734)
			(end -2.7559 -1.8034)
			(stroke
				(width 0.1524)
				(type default)
			)
			(layer "F.SilkS")
		)
		(fp_line
			(start -1.253236 -2.821432)
			(end -1.253236 -3.329432)
			(stroke
				(width 0.1524)
				(type default)
			)
			(layer "F.SilkS")
		)
		(fp_line
			(start 2.821432 0.23876)
			(end 3.329432 0.23876)
			(stroke
				(width 0.1524)
				(type default)
			)
			(layer "F.SilkS")
		)
		(fp_line
			(start -2.7559 1.8034)
			(end -2.7559 3.0734)
			(stroke
				(width 0.1524)
				(type default)
			)
			(layer "F.SilkS")
		)
		(fp_line
			(start 0.766064 2.796032)
			(end 0.766064 3.558032)
			(stroke
				(width 0.1524)
				(type default)
			)
			(layer "F.SilkS")
		)
		(fp_line
			(start 3.0861 3.0734)
			(end 3.0861 1.8034)
			(stroke
				(width 0.1524)
				(type default)
			)
			(layer "F.SilkS")
		)
		(fp_line
			(start 1.8161 3.0734)
			(end 3.0861 3.0734)
			(stroke
				(width 0.1524)
				(type default)
			)
			(layer "F.SilkS")
		)
		(fp_line
			(start -2.7559 3.0734)
			(end -1.4859 3.0734)
			(stroke
				(width 0.1524)
				(type default)
			)
			(layer "F.SilkS")
		)
		(fp_poly
			(pts
				(xy 3.0861 -3.0734) (xy 1.8161 -3.0734) (xy 3.0861 -1.8034)
			)
			(stroke
				(width 0)
				(type default)
			)
			(fill yes)
			(layer "F.SilkS")
		)
		(fp_rect
			(start -2.2479 2.2479)
			(end 2.2479 -2.2479)
			(stroke
				(width 0)
				(type default)
			)
			(fill no)
			(layer "F.CrtYd")
		)
		(fp_poly
			(pts
				(xy -2.7559 -3.0734) (xy -2.7559 3.0734) (xy 3.0861 3.0734) (xy 3.0861 2.0193) (xy 2.2479 2.0193)
				(xy 2.2479 2.2479) (xy -2.2479 2.2479) (xy -2.2479 -2.2479) (xy 2.2479 -2.2479) (xy 2.2479 2.0066)
				(xy 3.0861 2.0066) (xy 3.0861 -3.0734)
			)
			(stroke
				(width 0)
				(type default)
			)
			(fill no)
			(layer "F.CrtYd")
		)
		(fp_rect
			(start -2.7559 3.0734)
			(end 3.0861 -3.0734)
			(stroke
				(width 0)
				(type default)
			)
			(fill no)
			(layer "F.Fab")
		)
		(pad "1" smd rect
			(at 1.249934 -2.135632 90)
			(size 0.3556 0.8382)
			(layers "F.Cu" "F.Mask" "F.Paste")
			(net "AGND_P0V9_C")
		)
		(pad "2" smd rect
			(at 0.750062 -2.135632 90)
			(size 0.3556 0.8382)
			(layers "F.Cu" "F.Mask" "F.Paste")
			(net "Net_1133")
		)
		(pad "3" smd rect
			(at 0.249936 -2.135632 90)
			(size 0.3556 0.8382)
			(layers "F.Cu" "F.Mask" "F.Paste")
			(net "VT235_AVDD")
		)
		(pad "4" smd rect
			(at -0.249936 -0.687832 90)
			(size 0.3556 3.7338)
			(layers "F.Cu" "F.Mask" "F.Paste")
			(net "VT235_VDDH")
		)
		(pad "5" smd rect
			(at -1.249934 -1.335532 90)
			(size 0.3556 2.4384)
			(layers "F.Cu" "F.Mask" "F.Paste")
			(net "GND")
		)
		(pad "6" smd rect
			(at -1.75006 1.335532 90)
			(size 0.3556 2.4384)
			(layers "F.Cu" "F.Mask" "F.Paste")
			(net "VT235_VX")
		)
		(pad "7" smd rect
			(at -0.750062 1.335532 90)
			(size 0.3556 2.4384)
			(layers "F.Cu" "F.Mask" "F.Paste")
			(net "VT235_VX")
		)
		(pad "8" smd rect
			(at -0.249936 2.135632 90)
			(size 0.3556 0.8382)
			(layers "F.Cu" "F.Mask" "F.Paste")
			(net "VT235_BST")
		)
		(pad "9" smd rect
			(at 0.249936 2.135632 90)
			(size 0.3556 0.8382)
			(layers "F.Cu" "F.Mask" "F.Paste")
			(net "VT235_VDDL")
		)
		(pad "10" smd rect
			(at 0.750062 2.135632 90)
			(size 0.3556 0.8382)
			(layers "F.Cu" "F.Mask" "F.Paste")
			(net "VT235_AVDD")
		)
		(pad "11" smd rect
			(at 1.249934 2.135632 90)
			(size 0.3556 0.8382)
			(layers "F.Cu" "F.Mask" "F.Paste")
			(net "VT235_VFB")
		)
		(pad "12" smd rect
			(at 2.135632 1.75006 90)
			(size 0.8382 0.3556)
			(layers "F.Cu" "F.Mask" "F.Paste")
			(net "VT235_PGIN")
		)
		(pad "13" smd rect
			(at 2.135632 1.249934 90)
			(size 0.8382 0.3556)
			(layers "F.Cu" "F.Mask" "F.Paste")
			(net "VT235_VDES")
		)
		(pad "14" smd rect
			(at 2.135632 0.750062 90)
			(size 0.8382 0.3556)
			(layers "F.Cu" "F.Mask" "F.Paste")
			(net "VT235_VREF")
		)
		(pad "15" smd rect
			(at 2.135632 0.249936 90)
			(size 0.8382 0.3556)
			(layers "F.Cu" "F.Mask" "F.Paste")
			(net "VT235_BIAS")
		)
		(pad "16" smd rect
			(at 2.135632 -0.249936 90)
			(size 0.8382 0.3556)
			(layers "F.Cu" "F.Mask" "F.Paste")
			(net "VT235_IMAX")
		)
		(pad "17" smd rect
			(at 2.135632 -0.750062 90)
			(size 0.8382 0.3556)
			(layers "F.Cu" "F.Mask" "F.Paste")
			(net "PG_STAT_P0V955_C")
		)
		(pad "18" smd rect
			(at 2.135632 -1.249934 90)
			(size 0.8382 0.3556)
			(layers "F.Cu" "F.Mask" "F.Paste")
			(net "VT235_EN")
		)
		(pad "19" smd rect
			(at 2.135632 -1.75006 90)
			(size 0.8382 0.3556)
			(layers "F.Cu" "F.Mask" "F.Paste")
			(net "VT235_IRIP")
		)
	)
	(footprint ""
		(layer "F.Cu")
		(at 112.846612 -221.996 180)
		(property "Reference" "SR884"
			(at 0 0 180)
			(layer "F.SilkS")
			(hide yes)
			(effects
				(font
					(size 1.27 1.27)
				)
			)
		)
		(property "Value" "0R2J-2-GP"
			(at 0.064008 -3.993896 180)
			(unlocked yes)
			(layer "F.Fab")
			(hide yes)
			(effects
				(font
					(size 1.016 1.016)
					(thickness 0.1524)
				)
			)
		)
		(property "Device Type" "R402H16"
			(at 0.064008 -5.517896 180)
			(unlocked yes)
			(layer "F.Fab")
			(hide yes)
			(effects
				(font
					(size 1.016 1.016)
					(thickness 0.1524)
				)
			)
		)
		(duplicate_pad_numbers_are_jumpers no)
		(fp_line
			(start 0.508 -0.9398)
			(end -0.508 -0.9398)
			(stroke
				(width 0.1524)
				(type default)
			)
			(layer "F.SilkS")
		)
		(fp_line
			(start -0.508 -0.9398)
			(end -0.508 0.9398)
			(stroke
				(width 0.1524)
				(type default)
			)
			(layer "F.SilkS")
		)
		(fp_rect
			(start -0.508 0.9398)
			(end 0.508 -0.9398)
			(stroke
				(width 0)
				(type default)
			)
			(fill no)
			(layer "F.CrtYd")
		)
		(fp_rect
			(start -0.508 0.9398)
			(end 0.508 -0.9398)
			(stroke
				(width 0)
				(type default)
			)
			(fill no)
			(layer "F.Fab")
		)
		(pad "1" smd custom
			(at 0 -0.4445 180)
			(size 0.1397 0.1397)
			(layers "F.Cu" "F.Mask" "F.Paste")
			(net "REDV_TX8_N")
			(options
				(clearance outline)
				(anchor circle)
			)
			(primitives
				(gr_poly
					(pts
						(arc
							(start -0.1778 -0.2794)
							(mid -0.249642 -0.249642)
							(end -0.2794 -0.1778)
						)
						(arc
							(start -0.2794 0.1778)
							(mid -0.249642 0.249642)
							(end -0.1778 0.2794)
						)
						(arc
							(start 0.1778 0.2794)
							(mid 0.249642 0.249642)
							(end 0.2794 0.1778)
						)
						(arc
							(start 0.2794 -0.1778)
							(mid 0.249642 -0.249642)
							(end 0.1778 -0.2794)
						)
					)
					(width 0)
					(fill yes)
				)
			)
		)
		(pad "2" smd custom
			(at 0 0.4445 180)
			(size 0.1397 0.1397)
			(layers "F.Cu" "F.Mask" "F.Paste")
			(net "SAS_HDD_CONN_TX8_N")
			(options
				(clearance outline)
				(anchor circle)
			)
			(primitives
				(gr_poly
					(pts
						(arc
							(start -0.1778 -0.2794)
							(mid -0.249642 -0.249642)
							(end -0.2794 -0.1778)
						)
						(arc
							(start -0.2794 0.1778)
							(mid -0.249642 0.249642)
							(end -0.1778 0.2794)
						)
						(arc
							(start 0.1778 0.2794)
							(mid 0.249642 0.249642)
							(end 0.2794 0.1778)
						)
						(arc
							(start 0.2794 -0.1778)
							(mid 0.249642 -0.249642)
							(end 0.1778 -0.2794)
						)
					)
					(width 0)
					(fill yes)
				)
			)
		)
	)
	(footprint ""
		(layer "F.Cu")
		(at 277.495 -115.824)
		(property "Reference" "PR180"
			(at 0 0 0)
			(layer "F.SilkS")
			(hide yes)
			(effects
				(font
					(size 1.27 1.27)
				)
			)
		)
		(property "Value" "0R2J-2-GP"
			(at 0.064008 -3.993896 0)
			(unlocked yes)
			(layer "F.Fab")
			(hide yes)
			(effects
				(font
					(size 1.016 1.016)
					(thickness 0.1524)
				)
			)
		)
		(property "Device Type" "R402H16"
			(at 0.064008 -5.517896 0)
			(unlocked yes)
			(layer "F.Fab")
			(hide yes)
			(effects
				(font
					(size 1.016 1.016)
					(thickness 0.1524)
				)
			)
		)
		(duplicate_pad_numbers_are_jumpers no)
		(fp_line
			(start -0.508 -0.9398)
			(end -0.508 0.9398)
			(stroke
				(width 0.1524)
				(type default)
			)
			(layer "F.SilkS")
		)
		(fp_line
			(start 0.508 -0.9398)
			(end -0.508 -0.9398)
			(stroke
				(width 0.1524)
				(type default)
			)
			(layer "F.SilkS")
		)
		(fp_rect
			(start -0.508 0.9398)
			(end 0.508 -0.9398)
			(stroke
				(width 0)
				(type default)
			)
			(fill no)
			(layer "F.CrtYd")
		)
		(fp_rect
			(start -0.508 0.9398)
			(end 0.508 -0.9398)
			(stroke
				(width 0)
				(type default)
			)
			(fill no)
			(layer "F.Fab")
		)
		(pad "1" smd custom
			(at 0 -0.4445)
			(size 0.1397 0.1397)
			(layers "F.Cu" "F.Mask" "F.Paste")
			(net "BMC_1V8_C_EN")
			(options
				(clearance outline)
				(anchor circle)
			)
			(primitives
				(gr_poly
					(pts
						(arc
							(start -0.1778 -0.2794)
							(mid -0.249642 -0.249642)
							(end -0.2794 -0.1778)
						)
						(arc
							(start -0.2794 0.1778)
							(mid -0.249642 0.249642)
							(end -0.1778 0.2794)
						)
						(arc
							(start 0.1778 0.2794)
							(mid 0.249642 0.249642)
							(end 0.2794 0.1778)
						)
						(arc
							(start 0.2794 -0.1778)
							(mid 0.249642 -0.249642)
							(end 0.1778 -0.2794)
						)
					)
					(width 0)
					(fill yes)
				)
			)
		)
		(pad "2" smd custom
			(at 0 0.4445)
			(size 0.1397 0.1397)
			(layers "F.Cu" "F.Mask" "F.Paste")
			(net "P1V8_C_EN_B")
			(options
				(clearance outline)
				(anchor circle)
			)
			(primitives
				(gr_poly
					(pts
						(arc
							(start -0.1778 -0.2794)
							(mid -0.249642 -0.249642)
							(end -0.2794 -0.1778)
						)
						(arc
							(start -0.2794 0.1778)
							(mid -0.249642 0.249642)
							(end -0.1778 0.2794)
						)
						(arc
							(start 0.1778 0.2794)
							(mid 0.249642 0.249642)
							(end 0.2794 0.1778)
						)
						(arc
							(start 0.2794 -0.1778)
							(mid 0.249642 -0.249642)
							(end 0.1778 -0.2794)
						)
					)
					(width 0)
					(fill yes)
				)
			)
		)
	)
	(footprint ""
		(layer "F.Cu")
		(at 111.887 -61.976 -90)
		(property "Reference" "SR732"
			(at 0 0 270)
			(layer "F.SilkS")
			(hide yes)
			(effects
				(font
					(size 1.27 1.27)
				)
			)
		)
		(property "Value" "10KR2F-2-GP"
			(at 0.064008 -3.993896 270)
			(unlocked yes)
			(layer "F.Fab")
			(hide yes)
			(effects
				(font
					(size 1.016 1.016)
					(thickness 0.1524)
				)
			)
		)
		(property "Device Type" "R402H16"
			(at 0.064008 -5.517896 270)
			(unlocked yes)
			(layer "F.Fab")
			(hide yes)
			(effects
				(font
					(size 1.016 1.016)
					(thickness 0.1524)
				)
			)
		)
		(duplicate_pad_numbers_are_jumpers no)
		(fp_line
			(start -0.508 -0.9398)
			(end -0.508 0.9398)
			(stroke
				(width 0.1524)
				(type default)
			)
			(layer "F.SilkS")
		)
		(fp_line
			(start 0.508 -0.9398)
			(end -0.508 -0.9398)
			(stroke
				(width 0.1524)
				(type default)
			)
			(layer "F.SilkS")
		)
		(fp_rect
			(start -0.508 0.9398)
			(end 0.508 -0.9398)
			(stroke
				(width 0)
				(type default)
			)
			(fill no)
			(layer "F.CrtYd")
		)
		(fp_rect
			(start -0.508 0.9398)
			(end 0.508 -0.9398)
			(stroke
				(width 0)
				(type default)
			)
			(fill no)
			(layer "F.Fab")
		)
		(pad "1" smd custom
			(at 0 -0.4445 270)
			(size 0.1397 0.1397)
			(layers "F.Cu" "F.Mask" "F.Paste")
			(net "P1V8_C")
			(options
				(clearance outline)
				(anchor circle)
			)
			(primitives
				(gr_poly
					(pts
						(arc
							(start -0.1778 -0.2794)
							(mid -0.249642 -0.249642)
							(end -0.2794 -0.1778)
						)
						(arc
							(start -0.2794 0.1778)
							(mid -0.249642 0.249642)
							(end -0.1778 0.2794)
						)
						(arc
							(start 0.1778 0.2794)
							(mid 0.249642 0.249642)
							(end 0.2794 0.1778)
						)
						(arc
							(start 0.2794 -0.1778)
							(mid 0.249642 -0.249642)
							(end 0.1778 -0.2794)
						)
					)
					(width 0)
					(fill yes)
				)
			)
		)
		(pad "2" smd custom
			(at 0 0.4445 270)
			(size 0.1397 0.1397)
			(layers "F.Cu" "F.Mask" "F.Paste")
			(net "XM_CS0_N")
			(options
				(clearance outline)
				(anchor circle)
			)
			(primitives
				(gr_poly
					(pts
						(arc
							(start -0.1778 -0.2794)
							(mid -0.249642 -0.249642)
							(end -0.2794 -0.1778)
						)
						(arc
							(start -0.2794 0.1778)
							(mid -0.249642 0.249642)
							(end -0.1778 0.2794)
						)
						(arc
							(start 0.1778 0.2794)
							(mid 0.249642 0.249642)
							(end 0.2794 0.1778)
						)
						(arc
							(start 0.2794 -0.1778)
							(mid 0.249642 -0.249642)
							(end 0.1778 -0.2794)
						)
					)
					(width 0)
					(fill yes)
				)
			)
		)
	)
	(footprint ""
		(layer "F.Cu")
		(at 199.771 -103.759)
		(property "Reference" "PL12"
			(at 0 0 0)
			(layer "F.SilkS")
			(hide yes)
			(effects
				(font
					(size 1.27 1.27)
				)
			)
		)
		(property "Value" "COIL-3D3UH-26-GP"
			(at -4.699 -4.0132 0)
			(unlocked yes)
			(layer "F.Fab")
			(hide yes)
			(effects
				(font
					(size 1.016 1.016)
					(thickness 0.1524)
				)
			)
		)
		(property "Device Type" "L7066-1830-UH119"
			(at -4.699 -5.5372 0)
			(unlocked yes)
			(layer "F.Fab")
			(hide yes)
			(effects
				(font
					(size 1.016 1.016)
					(thickness 0.1524)
				)
			)
		)
		(duplicate_pad_numbers_are_jumpers no)
		(fp_line
			(start -3.556 -4.4958)
			(end 3.556 -4.4958)
			(stroke
				(width 0.1524)
				(type default)
			)
			(layer "F.SilkS")
		)
		(fp_line
			(start -3.556 4.4958)
			(end -3.556 -4.4958)
			(stroke
				(width 0.1524)
				(type default)
			)
			(layer "F.SilkS")
		)
		(fp_line
			(start 3.556 -4.4958)
			(end 3.556 4.4958)
			(stroke
				(width 0.1524)
				(type default)
			)
			(layer "F.SilkS")
		)
		(fp_line
			(start 3.556 4.4958)
			(end -3.556 4.4958)
			(stroke
				(width 0.1524)
				(type default)
			)
			(layer "F.SilkS")
		)
		(fp_rect
			(start -3.302 3.4798)
			(end 3.302 -3.4798)
			(stroke
				(width 0)
				(type default)
			)
			(fill no)
			(layer "F.CrtYd")
		)
		(fp_poly
			(pts
				(xy -3.81 4.572) (xy -3.81 -4.572) (xy 3.81 -4.572) (xy 3.81 -0.5588) (xy 3.302 -0.5588) (xy 3.302 -3.4798)
				(xy -3.302 -3.4798) (xy -3.302 3.4798) (xy 3.302 3.4798) (xy 3.302 -0.5461) (xy 3.81 -0.5461) (xy 3.81 4.572)
			)
			(stroke
				(width 0)
				(type default)
			)
			(fill no)
			(layer "F.CrtYd")
		)
		(fp_rect
			(start -3.81 4.572)
			(end 3.81 -4.572)
			(stroke
				(width 0)
				(type default)
			)
			(fill no)
			(layer "F.Fab")
		)
		(pad "1" smd rect
			(at 0 -2.779522)
			(size 3.5052 2.921)
			(layers "F.Cu" "F.Mask" "F.Paste")
			(net "P1V5_E_SW")
		)
		(pad "2" smd rect
			(at 0 2.779522)
			(size 3.5052 2.921)
			(layers "F.Cu" "F.Mask" "F.Paste")
			(net "P1V5_E")
		)
	)
	(footprint ""
		(layer "F.Cu")
		(at 90.683842 -122.626882 90)
		(property "Reference" "SR751"
			(at 0 0 90)
			(layer "F.SilkS")
			(hide yes)
			(effects
				(font
					(size 1.27 1.27)
				)
			)
		)
		(property "Value" "200KR2F-L-GP"
			(at 0.064008 -3.993896 90)
			(unlocked yes)
			(layer "F.Fab")
			(hide yes)
			(effects
				(font
					(size 1.016 1.016)
					(thickness 0.1524)
				)
			)
		)
		(property "Device Type" "R402H16"
			(at 0.064008 -5.517896 90)
			(unlocked yes)
			(layer "F.Fab")
			(hide yes)
			(effects
				(font
					(size 1.016 1.016)
					(thickness 0.1524)
				)
			)
		)
		(duplicate_pad_numbers_are_jumpers no)
		(fp_line
			(start 0.508 -0.9398)
			(end -0.508 -0.9398)
			(stroke
				(width 0.1524)
				(type default)
			)
			(layer "F.SilkS")
		)
		(fp_line
			(start -0.508 -0.9398)
			(end -0.508 0.9398)
			(stroke
				(width 0.1524)
				(type default)
			)
			(layer "F.SilkS")
		)
		(fp_rect
			(start -0.508 0.9398)
			(end 0.508 -0.9398)
			(stroke
				(width 0)
				(type default)
			)
			(fill no)
			(layer "F.CrtYd")
		)
		(fp_rect
			(start -0.508 0.9398)
			(end 0.508 -0.9398)
			(stroke
				(width 0)
				(type default)
			)
			(fill no)
			(layer "F.Fab")
		)
		(pad "1" smd custom
			(at 0 -0.4445 90)
			(size 0.1397 0.1397)
			(layers "F.Cu" "F.Mask" "F.Paste")
			(net "EXP_I2C_VREF_0")
			(options
				(clearance outline)
				(anchor circle)
			)
			(primitives
				(gr_poly
					(pts
						(arc
							(start -0.1778 -0.2794)
							(mid -0.249642 -0.249642)
							(end -0.2794 -0.1778)
						)
						(arc
							(start -0.2794 0.1778)
							(mid -0.249642 0.249642)
							(end -0.1778 0.2794)
						)
						(arc
							(start 0.1778 0.2794)
							(mid 0.249642 0.249642)
							(end 0.2794 0.1778)
						)
						(arc
							(start 0.2794 -0.1778)
							(mid 0.249642 -0.249642)
							(end 0.1778 -0.2794)
						)
					)
					(width 0)
					(fill yes)
				)
			)
		)
		(pad "2" smd custom
			(at 0 0.4445 90)
			(size 0.1397 0.1397)
			(layers "F.Cu" "F.Mask" "F.Paste")
			(net "P3V3_STBY")
			(options
				(clearance outline)
				(anchor circle)
			)
			(primitives
				(gr_poly
					(pts
						(arc
							(start -0.1778 -0.2794)
							(mid -0.249642 -0.249642)
							(end -0.2794 -0.1778)
						)
						(arc
							(start -0.2794 0.1778)
							(mid -0.249642 0.249642)
							(end -0.1778 0.2794)
						)
						(arc
							(start 0.1778 0.2794)
							(mid 0.249642 0.249642)
							(end 0.2794 0.1778)
						)
						(arc
							(start 0.2794 -0.1778)
							(mid 0.249642 -0.249642)
							(end 0.1778 -0.2794)
						)
					)
					(width 0)
					(fill yes)
				)
			)
		)
	)
)
